# BASEBOARD_FAB2 (Tioga Pass) — schematic netlist excerpt (pin names and nets, part order shuffled) for the footprints in the layout excerpt that follows; sources: Cadence DE-HDL packaged netlist, KiCad conversion of Wiwynn_Tioga_Pass_MB.brd

J6U2  SCONN288_H44441003  SCONN  pkg PIP  page 48
  \12v\(1)  = P12V_NVDIMM_ABC
  VSS(93)  = GND
  DQ(4)  = M_C_DQ<4>
  VSS(92)  = GND
  DQ(0)  = M_C_DQ<0>
  VSS(91)  = GND
  DQS9P  = M_C_DQS_DP<9>
  DQS9N  = M_C_DQS_DN<9>
  VSS(90)  = GND
  DQ(6)  = M_C_DQ<6>
  VSS(89)  = GND
  DQ(2)  = M_C_DQ<2>
  VSS(88)  = GND
  DQ(12)  = M_C_DQ<12>
  VSS(87)  = GND
  DQ(8)  = M_C_DQ<8>
  VSS(86)  = GND
  DQS10P  = M_C_DQS_DP<10>
  DQS10N  = M_C_DQS_DN<10>
  VSS(85)  = GND
  DQ(14)  = M_C_DQ<14>
  VSS(84)  = GND
  DQ(10)  = M_C_DQ<10>
  VSS(83)  = GND
  DQ(20)  = M_C_DQ<20>
  VSS(82)  = GND
  DQ(16)  = M_C_DQ<16>
  VSS(81)  = GND
  DQS11P  = M_C_DQS_DP<11>
  DQS11N  = M_C_DQS_DN<11>
  VSS(80)  = GND
  DQ(22)  = M_C_DQ<22>
  VSS(79)  = GND
  DQ(18)  = M_C_DQ<18>
  VSS(78)  = GND
  DQ(28)  = M_C_DQ<28>
  VSS(77)  = GND
  DQ(24)  = M_C_DQ<24>
  VSS(76)  = GND
  DQS12P  = M_C_DQS_DP<12>
  DQS12N  = M_C_DQS_DN<12>
  VSS(75)  = GND
  DQ(30)  = M_C_DQ<30>
  VSS(74)  = GND
  DQ(26)  = M_C_DQ<26>
  VSS(73)  = GND
  CB(4)  = M_C_ECC<4>
  VSS(72)  = GND
  CB(0)  = M_C_ECC<0>
  VSS(71)  = GND
  DQS17P  = M_C_DQS_DP<17>
  DQS17N  = M_C_DQS_DN<17>
  VSS(70)  = GND
  CB(6)  = M_C_ECC<6>
  VSS(69)  = GND
  CB(2)  = M_C_ECC<2>
  VSS(68)  = GND
  RESET_N  = M_ABC_RST_N
  VDD(25)  = PVDDQ_ABC
  CKE(0)  = M_C_CKE<2>
  VDD(24)  = PVDDQ_ABC
  ACT_N  = M_C_ACT_N
  BG(0)  = M_C_BG<0>
  VDD(23)  = PVDDQ_ABC
  A12  = M_C_MA<12>
  A9  = M_C_MA<9>
  VDD(22)  = PVDDQ_ABC
  A8  = M_C_MA<8>
  A6  = M_C_MA<6>
  VDD(21)  = PVDDQ_ABC
  A3  = M_C_MA<3>
  A1  = M_C_MA<1>
  VDD(20)  = PVDDQ_ABC
  CK0P  = M_C_CLK_DP<2>
  CK0N  = M_C_CLK_DN<2>
  VDD(19)  = PVDDQ_ABC
  VTT(1)  = PVTT_ABC
  EVENT_N  = FM_DIMM_EVENT_COD_N
  A0  = M_C_MA<0>
  VDD(18)  = PVDDQ_ABC
  BA(0)  = M_C_BA<0>
  A16_RAS_N  = M_C_MA<16>
  VDD(17)  = PVDDQ_ABC
  S0_N  = M_C_CS_N<4>
  VDD(16)  = PVDDQ_ABC
  A15_CAS_N  = M_C_MA<15>
  ODT(0)  = M_C_ODT<2>
  VDD(15)  = PVDDQ_ABC
  S1_N  = M_C_CS_N<5>
  VDD(14)  = PVDDQ_ABC
  ODT(1)  = M_C_ODT<3>
  VDD(13)  = PVDDQ_ABC
  S2_N_C(0)  = M_C_CS_N<6>
  VSS(67)  = GND
  DQ(36)  = M_C_DQ<36>
  VSS(66)  = GND
  DQ(32)  = M_C_DQ<32>
  VSS(65)  = GND
  DQS13P  = M_C_DQS_DP<13>
  DQS13N  = M_C_DQS_DN<13>
  VSS(64)  = GND
  DQ(38)  = M_C_DQ<38>
  VSS(63)  = GND
  DQ(34)  = M_C_DQ<34>
  VSS(62)  = GND
  DQ(44)  = M_C_DQ<44>
  VSS(61)  = GND
  DQ(40)  = M_C_DQ<40>
  VSS(60)  = GND
  DQS14P  = M_C_DQS_DP<14>
  DQS14N  = M_C_DQS_DN<14>
  VSS(59)  = GND
  DQ(46)  = M_C_DQ<46>
  VSS(58)  = GND
  DQ(42)  = M_C_DQ<42>
  VSS(57)  = GND
  DQ(52)  = M_C_DQ<52>
  VSS(56)  = GND
  DQ(48)  = M_C_DQ<48>
  VSS(55)  = GND
  DQS15P  = M_C_DQS_DP<15>
  DQS15N  = M_C_DQS_DN<15>
  VSS(54)  = GND
  DQ(54)  = M_C_DQ<54>
  VSS(53)  = GND
  DQ(50)  = M_C_DQ<50>
  VSS(52)  = GND
  DQ(60)  = M_C_DQ<60>
  VSS(51)  = GND
  DQ(56)  = M_C_DQ<56>
  VSS(50)  = GND
  DQS16P  = M_C_DQS_DP<16>
  DQS16N  = M_C_DQS_DN<16>
  VSS(49)  = GND
  DQ(62)  = M_C_DQ<62>
  VSS(48)  = GND
  DQ(58)  = M_C_DQ<58>
  VSS(47)  = GND
  SA(0)  = PVPP_ABC
  SA(1)  = GND
  SCL  = SMB_DDR_ABC_VPP_SCL
  VPP(4)  = PVPP_ABC
  VPP(3)  = PVPP_ABC
  RFU(2)  = TP_CH_C_DIMM_C1_RFU_2
  \12v\(0)  = P12V_NVDIMM_ABC
  VREFCA  = M_C_VREF
  VSS(46)  = GND
  DQ(5)  = M_C_DQ<5>
  VSS(45)  = GND
  DQ(1)  = M_C_DQ<1>
  VSS(44)  = GND
  DQS0N  = M_C_DQS_DN<0>
  DQS0P  = M_C_DQS_DP<0>
  VSS(43)  = GND
  DQ(7)  = M_C_DQ<7>
  VSS(42)  = GND
  DQ(3)  = M_C_DQ<3>
  VSS(41)  = GND
  DQ(13)  = M_C_DQ<13>
  VSS(40)  = GND
  DQ(9)  = M_C_DQ<9>
  VSS(39)  = GND
  DQS1N  = M_C_DQS_DN<1>
  DQS1P  = M_C_DQS_DP<1>
  VSS(38)  = GND
  DQ(15)  = M_C_DQ<15>
  VSS(37)  = GND
  DQ(11)  = M_C_DQ<11>
  VSS(36)  = GND
  DQ(21)  = M_C_DQ<21>
  VSS(35)  = GND
  DQ(17)  = M_C_DQ<17>
  VSS(34)  = GND
  DQS2N  = M_C_DQS_DN<2>
  DQS2P  = M_C_DQS_DP<2>
  VSS(33)  = GND
  DQ(23)  = M_C_DQ<23>
  VSS(32)  = GND
  DQ(19)  = M_C_DQ<19>
  VSS(31)  = GND
  DQ(29)  = M_C_DQ<29>
  VSS(30)  = GND
  DQ(25)  = M_C_DQ<25>
  VSS(29)  = GND
  DQS3N  = M_C_DQS_DN<3>
  DQS3P  = M_C_DQS_DP<3>
  VSS(28)  = GND
  DQ(31)  = M_C_DQ<31>
  VSS(27)  = GND
  DQ(27)  = M_C_DQ<27>
  VSS(26)  = GND
  CB(5)  = M_C_ECC<5>
  VSS(25)  = GND
  CB(1)  = M_C_ECC<1>
  VSS(24)  = GND
  DQS8N  = M_C_DQS_DN<8>
  DQS8P  = M_C_DQS_DP<8>
  VSS(23)  = GND
  CB(7)  = M_C_ECC<7>
  VSS(22)  = GND
  CB(3)  = M_C_ECC<3>
  VSS(21)  = GND
  CKE(1)  = M_C_CKE<3>
  VDD(12)  = PVDDQ_ABC
  RFU(0)  = TP_CH_C_DIMM_C1_RFU_0
  VDD(11)  = PVDDQ_ABC
  BG(1)  = M_C_BG<1>
  ALERT_N  = M_C_ALERT_N
  VDD(10)  = PVDDQ_ABC
  A11  = M_C_MA<11>
  A7  = M_C_MA<7>
  VDD(9)  = PVDDQ_ABC
  A5  = M_C_MA<5>
  A4  = M_C_MA<4>
  VDD(8)  = PVDDQ_ABC
  A2  = M_C_MA<2>
  VDD(7)  = PVDDQ_ABC
  CK1P  = M_C_CLK_DP<3>
  CK1N  = M_C_CLK_DN<3>
  VDD(6)  = PVDDQ_ABC
  VTT(0)  = PVTT_ABC
  PAR  = M_C_PAR
  VDD(5)  = PVDDQ_ABC
  BA(1)  = M_C_BA<1>
  A10  = M_C_MA<10>
  VDD(4)  = PVDDQ_ABC
  RFU(1)  = TP_CH_C_DIMM_C1_RFU_1
  A14_WE_N  = M_C_MA<14>
  VDD(3)  = PVDDQ_ABC
  SAVE_N_NC  = FM_ADR_COMPLETE_ABC_N
  VDD(2)  = PVDDQ_ABC
  A13  = M_C_MA<13>
  VDD(1)  = PVDDQ_ABC
  A17  = M_C_MA<17>
  C(2)  = M_C_C<2>
  VDD(0)  = PVDDQ_ABC
  S3_N_C(1)  = M_C_CS_N<7>
  SA(2)  = PVPP_ABC
  VSS(20)  = GND
  DQ(37)  = M_C_DQ<37>
  VSS(19)  = GND
  DQ(33)  = M_C_DQ<33>
  VSS(18)  = GND
  DQS4N  = M_C_DQS_DN<4>
  DQS4P  = M_C_DQS_DP<4>
  VSS(17)  = GND
  DQ(39)  = M_C_DQ<39>
  VSS(16)  = GND
  DQ(35)  = M_C_DQ<35>
  VSS(15)  = GND
  DQ(45)  = M_C_DQ<45>
  VSS(14)  = GND
  DQ(41)  = M_C_DQ<41>
  VSS(13)  = GND
  DQS5N  = M_C_DQS_DN<5>
  DQS5P  = M_C_DQS_DP<5>
  VSS(12)  = GND
  DQ(47)  = M_C_DQ<47>
  VSS(11)  = GND
  DQ(43)  = M_C_DQ<43>
  VSS(10)  = GND
  DQ(53)  = M_C_DQ<53>
  VSS(9)  = GND
  DQ(49)  = M_C_DQ<49>
  VSS(8)  = GND
  DQS6N  = M_C_DQS_DN<6>
  DQS6P  = M_C_DQS_DP<6>
  VSS(7)  = GND
  DQ(55)  = M_C_DQ<55>
  VSS(6)  = GND
  DQ(51)  = M_C_DQ<51>
  VSS(5)  = GND
  DQ(61)  = M_C_DQ<61>
  VSS(4)  = GND
  DQ(57)  = M_C_DQ<57>
  VSS(3)  = GND
  DQS7N  = M_C_DQS_DN<7>
  DQS7P  = M_C_DQS_DP<7>
  VSS(2)  = GND
  DQ(63)  = M_C_DQ<63>
  VSS(1)  = GND
  DQ(59)  = M_C_DQ<59>
  VSS(0)  = GND
  VDDSPD  = PVPP_ABC
  SDA  = SMB_DDR_ABC_VPP_SDA
  VPP(1)  = PVPP_ABC
  VPP(0)  = PVPP_ABC
  VPP(2)  = PVPP_ABC

(kicad_pcb
	(version 20260206)
	(generator "pcbnew")
	(generator_version "10.0")
	(general
		(thickness 1.6)
		(legacy_teardrops no)
	)
	(paper "A4")
	(title_block
		(title "Wiwynn_Tioga_Pass_MB.brd")
		(comment 1 "Tioga Pass / footprint 2838 of 4770 (J6U2), pads 250-291 of 291")
	)
	(layers
		(0 "F.Cu" signal "TOP")
		(4 "In1.Cu" signal "L2GND")
		(6 "In2.Cu" signal "L3")
		(8 "In3.Cu" signal "L4GND")
		(10 "In4.Cu" signal "L5")
		(12 "In5.Cu" signal "L6GND")
		(14 "In6.Cu" signal "L7VCC")
		(16 "In7.Cu" signal "L8VCC")
		(18 "In8.Cu" signal "L9GND")
		(20 "In9.Cu" signal "L10")
		(22 "In10.Cu" signal "L11GND")
		(24 "In11.Cu" signal "L12")
		(26 "In12.Cu" signal "L13GND")
		(2 "B.Cu" signal "BOTTOM")
		(9 "F.Adhes" user "F.Adhesive")
		(11 "B.Adhes" user "B.Adhesive")
		(13 "F.Paste" user "Package Geometry/Pastemask Top")
		(15 "B.Paste" user "Package Geometry/Pastemask Bottom")
		(5 "F.SilkS" user "Ref Des/Silkscreen Top")
		(7 "B.SilkS" user "Ref Des/Silkscreen Bottom")
		(1 "F.Mask" user "Board Geometry/Soldermask Top")
		(3 "B.Mask" user "Board Geometry/Soldermask Bottom")
		(17 "Dwgs.User" user "User.Drawings")
		(19 "Cmts.User" user "User.Comments")
		(21 "Eco1.User" user "User.Eco1")
		(23 "Eco2.User" user "User.Eco2")
		(25 "Edge.Cuts" user "Board Geometry/Outline")
		(27 "Margin" user)
		(31 "F.CrtYd" user "Package Geometry/Place Bound Top")
		(29 "B.CrtYd" user "Package Geometry/Place Bound Bottom")
		(35 "F.Fab" user "Ref Des/Assembly Top")
		(33 "B.Fab" user "Ref Des/Assembly Bottom")
	)
	(footprint ""
		(layer "B.Cu")
		(at 194.700398 -5.621782 90)
		(property "Reference" "J6U2"
			(at 2.225548 39.48811 0)
			(unlocked yes)
			(layer "B.SilkS")
			(effects
				(font
					(size 0.7874 0.5842)
					(thickness 0.1524)
				)
				(justify left mirror)
			)
		)
		(property "Value" ""
			(at 0 0 90)
			(layer "B.Fab")
			(effects
				(font
					(size 1.27 1.27)
				)
				(justify mirror)
			)
		)
		(duplicate_pad_numbers_are_jumpers no)
		(pad "247" smd rect
			(at -4.59994 91.799918 270)
			(size 1.8034 0.508)
			(layers "B.Cu" "B.Mask" "B.Paste")
			(net "M_C_DQ<39>")
		)
		(pad "248" smd rect
			(at -4.59994 92.650056 270)
			(size 1.8034 0.508)
			(layers "B.Cu" "B.Mask" "B.Paste")
			(net "GND")
		)
		(pad "249" smd rect
			(at -4.59994 93.49994 270)
			(size 1.8034 0.508)
			(layers "B.Cu" "B.Mask" "B.Paste")
			(net "M_C_DQ<35>")
		)
		(pad "250" smd rect
			(at -4.59994 94.350078 270)
			(size 1.8034 0.508)
			(layers "B.Cu" "B.Mask" "B.Paste")
			(net "GND")
		)
		(pad "251" smd rect
			(at -4.59994 95.199962 270)
			(size 1.8034 0.508)
			(layers "B.Cu" "B.Mask" "B.Paste")
			(net "M_C_DQ<45>")
		)
		(pad "252" smd rect
			(at -4.59994 96.0501 270)
			(size 1.8034 0.508)
			(layers "B.Cu" "B.Mask" "B.Paste")
			(net "GND")
		)
		(pad "253" smd rect
			(at -4.59994 96.899984 270)
			(size 1.8034 0.508)
			(layers "B.Cu" "B.Mask" "B.Paste")
			(net "M_C_DQ<41>")
		)
		(pad "254" smd rect
			(at -4.59994 97.750122 270)
			(size 1.8034 0.508)
			(layers "B.Cu" "B.Mask" "B.Paste")
			(net "GND")
		)
		(pad "255" smd rect
			(at -4.59994 98.600006 270)
			(size 1.8034 0.508)
			(layers "B.Cu" "B.Mask" "B.Paste")
			(net "M_C_DQS_DN<5>")
		)
		(pad "256" smd rect
			(at -4.59994 99.44989 270)
			(size 1.8034 0.508)
			(layers "B.Cu" "B.Mask" "B.Paste")
			(net "M_C_DQS_DP<5>")
		)
		(pad "257" smd rect
			(at -4.59994 100.300028 270)
			(size 1.8034 0.508)
			(layers "B.Cu" "B.Mask" "B.Paste")
			(net "GND")
		)
		(pad "258" smd rect
			(at -4.59994 101.149912 270)
			(size 1.8034 0.508)
			(layers "B.Cu" "B.Mask" "B.Paste")
			(net "M_C_DQ<47>")
		)
		(pad "259" smd rect
			(at -4.59994 102.00005 270)
			(size 1.8034 0.508)
			(layers "B.Cu" "B.Mask" "B.Paste")
			(net "GND")
		)
		(pad "260" smd rect
			(at -4.59994 102.849934 270)
			(size 1.8034 0.508)
			(layers "B.Cu" "B.Mask" "B.Paste")
			(net "M_C_DQ<43>")
		)
		(pad "261" smd rect
			(at -4.59994 103.700072 270)
			(size 1.8034 0.508)
			(layers "B.Cu" "B.Mask" "B.Paste")
			(net "GND")
		)
		(pad "262" smd rect
			(at -4.59994 104.549956 270)
			(size 1.8034 0.508)
			(layers "B.Cu" "B.Mask" "B.Paste")
			(net "M_C_DQ<53>")
		)
		(pad "263" smd rect
			(at -4.59994 105.400094 270)
			(size 1.8034 0.508)
			(layers "B.Cu" "B.Mask" "B.Paste")
			(net "GND")
		)
		(pad "264" smd rect
			(at -4.59994 106.249978 270)
			(size 1.8034 0.508)
			(layers "B.Cu" "B.Mask" "B.Paste")
			(net "M_C_DQ<49>")
		)
		(pad "265" smd rect
			(at -4.59994 107.100116 270)
			(size 1.8034 0.508)
			(layers "B.Cu" "B.Mask" "B.Paste")
			(net "GND")
		)
		(pad "266" smd rect
			(at -4.59994 107.95 270)
			(size 1.8034 0.508)
			(layers "B.Cu" "B.Mask" "B.Paste")
			(net "M_C_DQS_DN<6>")
		)
		(pad "267" smd rect
			(at -4.59994 108.799884 270)
			(size 1.8034 0.508)
			(layers "B.Cu" "B.Mask" "B.Paste")
			(net "M_C_DQS_DP<6>")
		)
		(pad "268" smd rect
			(at -4.59994 109.650022 270)
			(size 1.8034 0.508)
			(layers "B.Cu" "B.Mask" "B.Paste")
			(net "GND")
		)
		(pad "269" smd rect
			(at -4.59994 110.499906 270)
			(size 1.8034 0.508)
			(layers "B.Cu" "B.Mask" "B.Paste")
			(net "M_C_DQ<55>")
		)
		(pad "270" smd rect
			(at -4.59994 111.350044 270)
			(size 1.8034 0.508)
			(layers "B.Cu" "B.Mask" "B.Paste")
			(net "GND")
		)
		(pad "271" smd rect
			(at -4.59994 112.199928 270)
			(size 1.8034 0.508)
			(layers "B.Cu" "B.Mask" "B.Paste")
			(net "M_C_DQ<51>")
		)
		(pad "272" smd rect
			(at -4.59994 113.050066 270)
			(size 1.8034 0.508)
			(layers "B.Cu" "B.Mask" "B.Paste")
			(net "GND")
		)
		(pad "273" smd rect
			(at -4.59994 113.89995 270)
			(size 1.8034 0.508)
			(layers "B.Cu" "B.Mask" "B.Paste")
			(net "M_C_DQ<61>")
		)
		(pad "274" smd rect
			(at -4.59994 114.750088 270)
			(size 1.8034 0.508)
			(layers "B.Cu" "B.Mask" "B.Paste")
			(net "GND")
		)
		(pad "275" smd rect
			(at -4.59994 115.599972 270)
			(size 1.8034 0.508)
			(layers "B.Cu" "B.Mask" "B.Paste")
			(net "M_C_DQ<57>")
		)
		(pad "276" smd rect
			(at -4.59994 116.45011 270)
			(size 1.8034 0.508)
			(layers "B.Cu" "B.Mask" "B.Paste")
			(net "GND")
		)
		(pad "277" smd rect
			(at -4.59994 117.299994 270)
			(size 1.8034 0.508)
			(layers "B.Cu" "B.Mask" "B.Paste")
			(net "M_C_DQS_DN<7>")
		)
		(pad "278" smd rect
			(at -4.59994 118.149878 270)
			(size 1.8034 0.508)
			(layers "B.Cu" "B.Mask" "B.Paste")
			(net "M_C_DQS_DP<7>")
		)
		(pad "279" smd rect
			(at -4.59994 119.000016 270)
			(size 1.8034 0.508)
			(layers "B.Cu" "B.Mask" "B.Paste")
			(net "GND")
		)
		(pad "280" smd rect
			(at -4.59994 119.8499 270)
			(size 1.8034 0.508)
			(layers "B.Cu" "B.Mask" "B.Paste")
			(net "M_C_DQ<63>")
		)
		(pad "281" smd rect
			(at -4.59994 120.700038 270)
			(size 1.8034 0.508)
			(layers "B.Cu" "B.Mask" "B.Paste")
			(net "GND")
		)
		(pad "282" smd rect
			(at -4.59994 121.549922 270)
			(size 1.8034 0.508)
			(layers "B.Cu" "B.Mask" "B.Paste")
			(net "M_C_DQ<59>")
		)
		(pad "283" smd rect
			(at -4.59994 122.40006 270)
			(size 1.8034 0.508)
			(layers "B.Cu" "B.Mask" "B.Paste")
			(net "GND")
		)
		(pad "284" smd rect
			(at -4.59994 123.249944 270)
			(size 1.8034 0.508)
			(layers "B.Cu" "B.Mask" "B.Paste")
			(net "PVPP_ABC")
		)
		(pad "285" smd rect
			(at -4.59994 124.100082 270)
			(size 1.8034 0.508)
			(layers "B.Cu" "B.Mask" "B.Paste")
			(net "SMB_DDR_ABC_VPP_SDA")
		)
		(pad "286" smd rect
			(at -4.59994 124.949966 270)
			(size 1.8034 0.508)
			(layers "B.Cu" "B.Mask" "B.Paste")
			(net "PVPP_ABC")
		)
		(pad "287" smd rect
			(at -4.59994 125.800104 270)
			(size 1.8034 0.508)
			(layers "B.Cu" "B.Mask" "B.Paste")
			(net "PVPP_ABC")
		)
		(pad "288" smd rect
			(at -4.59994 126.649988 270)
			(size 1.8034 0.508)
			(layers "B.Cu" "B.Mask" "B.Paste")
			(net "PVPP_ABC")
		)
	)
)
